# BASEBOARD_FAB2 (Tioga Pass) — schematic netlist excerpt (pin names and nets, part order shuffled) for the footprints in the layout excerpt that follows; sources: Cadence DE-HDL packaged netlist, KiCad conversion of Wiwynn_Tioga_Pass_MB.brd

R1D16  RES  69.8K 1% CHIP  pkg 0402  page 199 : A = A_HSC_ISET ; B = A_HSC_ISET_S2

(kicad_pcb
	(version 20260206)
	(generator "pcbnew")
	(generator_version "10.0")
	(general
		(thickness 1.6)
		(legacy_teardrops no)
	)
	(paper "A4")
	(title_block
		(title "Wiwynn_Tioga_Pass_MB.brd")
		(comment 1 "Tioga Pass / footprints 1949-1949 of 4770")
	)
	(layers
		(0 "F.Cu" signal "TOP")
		(4 "In1.Cu" signal "L2GND")
		(6 "In2.Cu" signal "L3")
		(8 "In3.Cu" signal "L4GND")
		(10 "In4.Cu" signal "L5")
		(12 "In5.Cu" signal "L6GND")
		(14 "In6.Cu" signal "L7VCC")
		(16 "In7.Cu" signal "L8VCC")
		(18 "In8.Cu" signal "L9GND")
		(20 "In9.Cu" signal "L10")
		(22 "In10.Cu" signal "L11GND")
		(24 "In11.Cu" signal "L12")
		(26 "In12.Cu" signal "L13GND")
		(2 "B.Cu" signal "BOTTOM")
		(9 "F.Adhes" user "F.Adhesive")
		(11 "B.Adhes" user "B.Adhesive")
		(13 "F.Paste" user "Package Geometry/Pastemask Top")
		(15 "B.Paste" user "Package Geometry/Pastemask Bottom")
		(5 "F.SilkS" user "Ref Des/Silkscreen Top")
		(7 "B.SilkS" user "Ref Des/Silkscreen Bottom")
		(1 "F.Mask" user "Board Geometry/Soldermask Top")
		(3 "B.Mask" user "Board Geometry/Soldermask Bottom")
		(17 "Dwgs.User" user "User.Drawings")
		(19 "Cmts.User" user "User.Comments")
		(21 "Eco1.User" user "User.Eco1")
		(23 "Eco2.User" user "User.Eco2")
		(25 "Edge.Cuts" user "Board Geometry/Outline")
		(27 "Margin" user)
		(31 "F.CrtYd" user "Package Geometry/Place Bound Top")
		(29 "B.CrtYd" user "Package Geometry/Place Bound Bottom")
		(35 "F.Fab" user "Ref Des/Assembly Top")
		(33 "B.Fab" user "Ref Des/Assembly Bottom")
	)
	(footprint ""
		(layer "F.Cu")
		(at 19.431 -82.423 -90)
		(property "Reference" "R1D16"
			(at 0 0 270)
			(layer "F.SilkS")
			(hide yes)
			(effects
				(font
					(size 1.27 1.27)
				)
			)
		)
		(property "Value" ""
			(at 0 0 270)
			(layer "F.Fab")
			(effects
				(font
					(size 1.27 1.27)
				)
			)
		)
		(duplicate_pad_numbers_are_jumpers no)
		(fp_poly
			(pts
				(xy -0.2794 -0.1016) (xy 0.2794 -0.1016) (xy 0.2794 0.9906) (xy -0.2794 0.9906)
			)
			(stroke
				(width 0)
				(type default)
			)
			(fill no)
			(layer "F.CrtYd")
		)
		(fp_line
			(start -0.2794 0.9906)
			(end 0.2794 0.9906)
			(stroke
				(width 0.1)
				(type default)
			)
			(layer "F.Fab")
		)
		(fp_line
			(start 0.2794 0.9906)
			(end 0.2794 -0.1016)
			(stroke
				(width 0.1)
				(type default)
			)
			(layer "F.Fab")
		)
		(fp_line
			(start -0.2794 -0.1016)
			(end -0.2794 0.9906)
			(stroke
				(width 0.1)
				(type default)
			)
			(layer "F.Fab")
		)
		(fp_line
			(start 0.2794 -0.1016)
			(end -0.2794 -0.1016)
			(stroke
				(width 0.1)
				(type default)
			)
			(layer "F.Fab")
		)
		(pad "1" smd rect
			(at 0 0 270)
			(size 0.508 0.508)
			(layers "F.Cu" "F.Mask" "F.Paste")
			(net "A_HSC_ISET")
		)
		(pad "2" smd rect
			(at 0 0.889 270)
			(size 0.508 0.508)
			(layers "F.Cu" "F.Mask" "F.Paste")
			(net "A_HSC_ISET_S2")
		)
		(zone
			(layer "F.Cu")
			(hatch none 0.5)
			(connect_pads
				(clearance 0)
			)
			(min_thickness 0.25)
			(keepout
				(tracks not_allowed)
				(vias allowed)
				(pads allowed)
				(copperpour not_allowed)
				(footprints allowed)
			)
			(placement
				(enabled no)
				(sheetname "")
			)
			(fill
				(thermal_gap 0.5)
				(thermal_bridge_width 0.5)
				(island_removal_mode 0)
			)
			(polygon
				(pts
					(xy 18.796 -82.677) (xy 18.796 -82.169) (xy 19.177 -82.169) (xy 19.177 -82.677)
				)
			)
		)
		(zone
			(layer "F.Cu")
			(hatch none 0.5)
			(connect_pads
				(clearance 0)
			)
			(min_thickness 0.25)
			(keepout
				(tracks allowed)
				(vias not_allowed)
				(pads allowed)
				(copperpour not_allowed)
				(footprints allowed)
			)
			(placement
				(enabled no)
				(sheetname "")
			)
			(fill
				(thermal_gap 0.5)
				(thermal_bridge_width 0.5)
				(island_removal_mode 0)
			)
			(polygon
				(pts
					(xy 19.177 -82.677) (xy 19.177 -82.169) (xy 18.796 -82.169) (xy 18.796 -82.677)
				)
			)
		)
	)
)
